(kicad_pcb
	(version 20260206)
	(generator "pcbnew")
	(generator_version "10.0")
	(general
		(thickness 1.6)
		(legacy_teardrops no)
	)
	(paper "A4")
	(title_block
		(title "panther-plus-userver — 13130-1b_20150205.brd")
		(comment 1 "Honey Badger (Wiwynn) / footprints 1134-1142 of 1509")
	)
	(layers
		(0 "F.Cu" signal "TOP")
		(4 "In1.Cu" signal "L2")
		(6 "In2.Cu" signal "L3")
		(8 "In3.Cu" signal "L4")
		(10 "In4.Cu" signal "L5")
		(12 "In5.Cu" signal "L6")
		(14 "In6.Cu" signal "L7")
		(16 "In7.Cu" signal "L8")
		(18 "In8.Cu" signal "L9")
		(20 "In9.Cu" signal "L10")
		(22 "In10.Cu" signal "L11")
		(2 "B.Cu" signal "BOTTOM")
		(9 "F.Adhes" user "F.Adhesive")
		(11 "B.Adhes" user "B.Adhesive")
		(13 "F.Paste" user "Package Geometry/Pastemask Top")
		(15 "B.Paste" user "Package Geometry/Pastemask Bottom")
		(5 "F.SilkS" user "Ref Des/Silkscreen Top")
		(7 "B.SilkS" user "Ref Des/Silkscreen Bottom")
		(1 "F.Mask" user "Board Geometry/Soldermask Top")
		(3 "B.Mask" user "Board Geometry/Soldermask Bottom")
		(17 "Dwgs.User" user "User.Drawings")
		(19 "Cmts.User" user "User.Comments")
		(21 "Eco1.User" user "User.Eco1")
		(23 "Eco2.User" user "User.Eco2")
		(25 "Edge.Cuts" user "Board Geometry/Outline")
		(27 "Margin" user)
		(31 "F.CrtYd" user "Package Geometry/Place Bound Top")
		(29 "B.CrtYd" user "Package Geometry/Place Bound Bottom")
		(35 "F.Fab" user "Ref Des/Assembly Top")
		(33 "B.Fab" user "Ref Des/Assembly Bottom")
	)
	(footprint ""
		(layer "B.Cu")
		(at 34.7726 -48.895 90)
		(property "Reference" "PR182"
			(at 0 0 90)
			(layer "B.SilkS")
			(hide yes)
			(effects
				(font
					(size 1.27 1.27)
				)
				(justify mirror)
			)
		)
		(property "Value" "0R2J-2-GP"
			(at -1.7907 -1.1176 90)
			(unlocked yes)
			(layer "B.Fab")
			(hide yes)
			(effects
				(font
					(size 1.016 1.016)
					(thickness 0.1524)
				)
				(justify mirror)
			)
		)
		(property "Device Type" "R402H16"
			(at -1.7907 -2.6416 90)
			(unlocked yes)
			(layer "B.Fab")
			(hide yes)
			(effects
				(font
					(size 1.016 1.016)
					(thickness 0.1524)
				)
				(justify mirror)
			)
		)
		(duplicate_pad_numbers_are_jumpers no)
		(fp_rect
			(start 0.381 0.8382)
			(end -0.381 -0.8382)
			(stroke
				(width 0)
				(type default)
			)
			(fill no)
			(layer "B.CrtYd")
		)
		(fp_rect
			(start 0.381 0.8382)
			(end -0.381 -0.8382)
			(stroke
				(width 0)
				(type default)
			)
			(fill no)
			(layer "B.Fab")
		)
		(pad "1" smd custom
			(at 0 -0.4318 270)
			(size 0.127 0.127)
			(layers "B.Cu" "B.Mask" "B.Paste")
			(net "P1V8_STBY_PG")
			(options
				(clearance outline)
				(anchor circle)
			)
			(primitives
				(gr_poly
					(pts
						(arc
							(start -0.2032 0.2794)
							(mid -0.239121 0.264521)
							(end -0.254 0.2286)
						)
						(arc
							(start -0.254 -0.2286)
							(mid -0.239121 -0.264521)
							(end -0.2032 -0.2794)
						)
						(arc
							(start 0.2032 -0.2794)
							(mid 0.239121 -0.264521)
							(end 0.254 -0.2286)
						)
						(arc
							(start 0.254 0.2286)
							(mid 0.239121 0.264521)
							(end 0.2032 0.2794)
						)
					)
					(width 0)
					(fill yes)
				)
			)
		)
		(pad "2" smd custom
			(at 0 0.4318 270)
			(size 0.127 0.127)
			(layers "B.Cu" "B.Mask" "B.Paste")
			(net "P1V5_STBY_EN")
			(options
				(clearance outline)
				(anchor circle)
			)
			(primitives
				(gr_poly
					(pts
						(arc
							(start -0.2032 0.2794)
							(mid -0.239121 0.264521)
							(end -0.254 0.2286)
						)
						(arc
							(start -0.254 -0.2286)
							(mid -0.239121 -0.264521)
							(end -0.2032 -0.2794)
						)
						(arc
							(start 0.2032 -0.2794)
							(mid 0.239121 -0.264521)
							(end 0.254 -0.2286)
						)
						(arc
							(start 0.254 0.2286)
							(mid 0.239121 0.264521)
							(end 0.2032 0.2794)
						)
					)
					(width 0)
					(fill yes)
				)
			)
		)
	)
	(footprint ""
		(layer "B.Cu")
		(at 41.656 -65.278 -90)
		(property "Reference" "PR35"
			(at 0 0 90)
			(layer "B.SilkS")
			(hide yes)
			(effects
				(font
					(size 1.27 1.27)
				)
				(justify mirror)
			)
		)
		(property "Value" "0R2J-2-GP"
			(at -1.7907 -1.1176 270)
			(unlocked yes)
			(layer "B.Fab")
			(hide yes)
			(effects
				(font
					(size 1.016 1.016)
					(thickness 0.1524)
				)
				(justify mirror)
			)
		)
		(property "Device Type" "R402H16"
			(at -1.7907 -2.6416 270)
			(unlocked yes)
			(layer "B.Fab")
			(hide yes)
			(effects
				(font
					(size 1.016 1.016)
					(thickness 0.1524)
				)
				(justify mirror)
			)
		)
		(duplicate_pad_numbers_are_jumpers no)
		(fp_rect
			(start 0.381 0.8382)
			(end -0.381 -0.8382)
			(stroke
				(width 0)
				(type default)
			)
			(fill no)
			(layer "B.CrtYd")
		)
		(fp_rect
			(start 0.381 0.8382)
			(end -0.381 -0.8382)
			(stroke
				(width 0)
				(type default)
			)
			(fill no)
			(layer "B.Fab")
		)
		(pad "1" smd custom
			(at 0 -0.4318 90)
			(size 0.127 0.127)
			(layers "B.Cu" "B.Mask" "B.Paste")
			(net "PVNN")
			(options
				(clearance outline)
				(anchor circle)
			)
			(primitives
				(gr_poly
					(pts
						(arc
							(start -0.2032 0.2794)
							(mid -0.239121 0.264521)
							(end -0.254 0.2286)
						)
						(arc
							(start -0.254 -0.2286)
							(mid -0.239121 -0.264521)
							(end -0.2032 -0.2794)
						)
						(arc
							(start 0.2032 -0.2794)
							(mid 0.239121 -0.264521)
							(end 0.254 -0.2286)
						)
						(arc
							(start 0.254 0.2286)
							(mid 0.239121 0.264521)
							(end 0.2032 0.2794)
						)
					)
					(width 0)
					(fill yes)
				)
			)
		)
		(pad "2" smd custom
			(at 0 0.4318 90)
			(size 0.127 0.127)
			(layers "B.Cu" "B.Mask" "B.Paste")
			(net "VR_PVNN_ISUMN_R2")
			(options
				(clearance outline)
				(anchor circle)
			)
			(primitives
				(gr_poly
					(pts
						(arc
							(start -0.2032 0.2794)
							(mid -0.239121 0.264521)
							(end -0.254 0.2286)
						)
						(arc
							(start -0.254 -0.2286)
							(mid -0.239121 -0.264521)
							(end -0.2032 -0.2794)
						)
						(arc
							(start 0.2032 -0.2794)
							(mid 0.239121 -0.264521)
							(end 0.254 -0.2286)
						)
						(arc
							(start 0.254 0.2286)
							(mid 0.239121 0.264521)
							(end 0.2032 0.2794)
						)
					)
					(width 0)
					(fill yes)
				)
			)
		)
	)
	(footprint ""
		(layer "B.Cu")
		(at 103.502968 -41.842436 -90)
		(property "Reference" "TP27"
			(at 0 0 90)
			(layer "B.SilkS")
			(hide yes)
			(effects
				(font
					(size 1.27 1.27)
				)
				(justify mirror)
			)
		)
		(property "Value" "TPAD24"
			(at 0 -2.9972 270)
			(unlocked yes)
			(layer "B.Fab")
			(hide yes)
			(effects
				(font
					(size 1.016 1.016)
					(thickness 0.1524)
				)
				(justify mirror)
			)
		)
		(property "Device Type" "TPAD24"
			(at 0 -4.5212 270)
			(unlocked yes)
			(layer "B.Fab")
			(hide yes)
			(effects
				(font
					(size 1.016 1.016)
					(thickness 0.1524)
				)
				(justify mirror)
			)
		)
		(duplicate_pad_numbers_are_jumpers no)
		(fp_poly
			(pts
				(arc
					(start 0 -0.3048)
					(mid 0 0.3048)
					(end 0 -0.3048)
				)
			)
			(stroke
				(width 0)
				(type default)
			)
			(fill no)
			(layer "B.CrtYd")
		)
		(fp_poly
			(pts
				(arc
					(start 0 -0.6096)
					(mid 0 0.6096)
					(end 0 -0.6096)
				)
			)
			(stroke
				(width 0)
				(type default)
			)
			(fill no)
			(layer "B.Fab")
		)
		(pad "1" smd circle
			(at 0 0 90)
			(size 0.6096 0.6096)
			(layers "B.Cu" "B.Mask" "B.Paste")
			(net "TP_CPU_RSVD6")
		)
	)
	(footprint ""
		(layer "B.Cu")
		(at 8.255 -22.606 180)
		(property "Reference" "PR120"
			(at 0 0 0)
			(layer "B.SilkS")
			(hide yes)
			(effects
				(font
					(size 1.27 1.27)
				)
				(justify mirror)
			)
		)
		(property "Value" "100KR2F-L1-GP"
			(at -1.7907 -1.1176 180)
			(unlocked yes)
			(layer "B.Fab")
			(hide yes)
			(effects
				(font
					(size 1.016 1.016)
					(thickness 0.1524)
				)
				(justify mirror)
			)
		)
		(property "Device Type" "R402H16"
			(at -1.7907 -2.6416 180)
			(unlocked yes)
			(layer "B.Fab")
			(hide yes)
			(effects
				(font
					(size 1.016 1.016)
					(thickness 0.1524)
				)
				(justify mirror)
			)
		)
		(duplicate_pad_numbers_are_jumpers no)
		(fp_rect
			(start 0.381 0.8382)
			(end -0.381 -0.8382)
			(stroke
				(width 0)
				(type default)
			)
			(fill no)
			(layer "B.CrtYd")
		)
		(fp_rect
			(start 0.381 0.8382)
			(end -0.381 -0.8382)
			(stroke
				(width 0)
				(type default)
			)
			(fill no)
			(layer "B.Fab")
		)
		(pad "1" smd custom
			(at 0 -0.4318)
			(size 0.127 0.127)
			(layers "B.Cu" "B.Mask" "B.Paste")
			(net "AGND_P1V0")
			(options
				(clearance outline)
				(anchor circle)
			)
			(primitives
				(gr_poly
					(pts
						(arc
							(start -0.2032 0.2794)
							(mid -0.239121 0.264521)
							(end -0.254 0.2286)
						)
						(arc
							(start -0.254 -0.2286)
							(mid -0.239121 -0.264521)
							(end -0.2032 -0.2794)
						)
						(arc
							(start 0.2032 -0.2794)
							(mid 0.239121 -0.264521)
							(end 0.254 -0.2286)
						)
						(arc
							(start 0.254 0.2286)
							(mid 0.239121 0.264521)
							(end 0.2032 0.2794)
						)
					)
					(width 0)
					(fill yes)
				)
			)
		)
		(pad "2" smd custom
			(at 0 0.4318)
			(size 0.127 0.127)
			(layers "B.Cu" "B.Mask" "B.Paste")
			(net "P1V0_MODE")
			(options
				(clearance outline)
				(anchor circle)
			)
			(primitives
				(gr_poly
					(pts
						(arc
							(start -0.2032 0.2794)
							(mid -0.239121 0.264521)
							(end -0.254 0.2286)
						)
						(arc
							(start -0.254 -0.2286)
							(mid -0.239121 -0.264521)
							(end -0.2032 -0.2794)
						)
						(arc
							(start 0.2032 -0.2794)
							(mid 0.239121 -0.264521)
							(end 0.254 -0.2286)
						)
						(arc
							(start 0.254 0.2286)
							(mid 0.239121 0.264521)
							(end 0.2032 0.2794)
						)
					)
					(width 0)
					(fill yes)
				)
			)
		)
	)
	(footprint ""
		(layer "B.Cu")
		(at 84.328 -64.516 90)
		(property "Reference" "R280"
			(at 0 0 90)
			(layer "B.SilkS")
			(hide yes)
			(effects
				(font
					(size 1.27 1.27)
				)
				(justify mirror)
			)
		)
		(property "Value" "1KR2F-3-GP"
			(at -0.064008 -3.993896 90)
			(unlocked yes)
			(layer "B.Fab")
			(hide yes)
			(effects
				(font
					(size 1.016 1.016)
					(thickness 0.1524)
				)
				(justify mirror)
			)
		)
		(property "Device Type" "R402H16"
			(at -0.064008 -5.517896 90)
			(unlocked yes)
			(layer "B.Fab")
			(hide yes)
			(effects
				(font
					(size 1.016 1.016)
					(thickness 0.1524)
				)
				(justify mirror)
			)
		)
		(duplicate_pad_numbers_are_jumpers no)
		(fp_rect
			(start 0.381 0.8382)
			(end -0.381 -0.8382)
			(stroke
				(width 0)
				(type default)
			)
			(fill no)
			(layer "B.CrtYd")
		)
		(fp_rect
			(start 0.381 0.8382)
			(end -0.381 -0.8382)
			(stroke
				(width 0)
				(type default)
			)
			(fill no)
			(layer "B.Fab")
		)
		(pad "1" smd custom
			(at 0 -0.4318 270)
			(size 0.127 0.127)
			(layers "B.Cu" "B.Mask" "B.Paste")
			(net "P1V0")
			(options
				(clearance outline)
				(anchor circle)
			)
			(primitives
				(gr_poly
					(pts
						(arc
							(start -0.2032 0.2794)
							(mid -0.239121 0.264521)
							(end -0.254 0.2286)
						)
						(arc
							(start -0.254 -0.2286)
							(mid -0.239121 -0.264521)
							(end -0.2032 -0.2794)
						)
						(arc
							(start 0.2032 -0.2794)
							(mid 0.239121 -0.264521)
							(end 0.254 -0.2286)
						)
						(arc
							(start 0.254 0.2286)
							(mid 0.239121 0.264521)
							(end 0.2032 0.2794)
						)
					)
					(width 0)
					(fill yes)
				)
			)
		)
		(pad "2" smd custom
			(at 0 0.4318 270)
			(size 0.127 0.127)
			(layers "B.Cu" "B.Mask" "B.Paste")
			(net "H_PROCESSOR_HOT_N_R")
			(options
				(clearance outline)
				(anchor circle)
			)
			(primitives
				(gr_poly
					(pts
						(arc
							(start -0.2032 0.2794)
							(mid -0.239121 0.264521)
							(end -0.254 0.2286)
						)
						(arc
							(start -0.254 -0.2286)
							(mid -0.239121 -0.264521)
							(end -0.2032 -0.2794)
						)
						(arc
							(start 0.2032 -0.2794)
							(mid 0.239121 -0.264521)
							(end 0.254 -0.2286)
						)
						(arc
							(start 0.254 0.2286)
							(mid 0.239121 0.264521)
							(end 0.2032 0.2794)
						)
					)
					(width 0)
					(fill yes)
				)
			)
		)
	)
	(footprint ""
		(layer "B.Cu")
		(at 65.8622 -19.3548 90)
		(property "Reference" "PC126"
			(at 0 0 90)
			(layer "B.SilkS")
			(hide yes)
			(effects
				(font
					(size 1.27 1.27)
				)
				(justify mirror)
			)
		)
		(property "Value" "SC5P50V2CN-2GP"
			(at -1.8923 -1.2065 90)
			(unlocked yes)
			(layer "B.Fab")
			(hide yes)
			(effects
				(font
					(size 1.016 1.016)
					(thickness 0.1524)
				)
				(justify mirror)
			)
		)
		(property "Device Type" "C402H22"
			(at -1.8923 -2.7305 90)
			(unlocked yes)
			(layer "B.Fab")
			(hide yes)
			(effects
				(font
					(size 1.016 1.016)
					(thickness 0.1524)
				)
				(justify mirror)
			)
		)
		(duplicate_pad_numbers_are_jumpers no)
		(fp_rect
			(start 0.381 0.7366)
			(end -0.381 -0.7366)
			(stroke
				(width 0)
				(type default)
			)
			(fill no)
			(layer "B.CrtYd")
		)
		(fp_rect
			(start 0.381 0.7366)
			(end -0.381 -0.7366)
			(stroke
				(width 0)
				(type default)
			)
			(fill no)
			(layer "B.Fab")
		)
		(pad "1" smd custom
			(at 0 -0.4572 270)
			(size 0.1143 0.1143)
			(layers "B.Cu" "B.Mask" "B.Paste")
			(net "VR_FB_R_P1V8_STBY")
			(options
				(clearance outline)
				(anchor circle)
			)
			(primitives
				(gr_poly
					(pts
						(arc
							(start -0.254 0.1778)
							(mid -0.239121 0.213721)
							(end -0.2032 0.2286)
						)
						(arc
							(start 0.2032 0.2286)
							(mid 0.239121 0.213721)
							(end 0.254 0.1778)
						)
						(arc
							(start 0.254 -0.1778)
							(mid 0.239121 -0.213721)
							(end 0.2032 -0.2286)
						)
						(arc
							(start -0.2032 -0.2286)
							(mid -0.239121 -0.213721)
							(end -0.254 -0.1778)
						)
					)
					(width 0)
					(fill yes)
				)
			)
		)
		(pad "2" smd custom
			(at 0 0.4572 270)
			(size 0.1143 0.1143)
			(layers "B.Cu" "B.Mask" "B.Paste")
			(net "VR_FB_P1V8_STBY")
			(options
				(clearance outline)
				(anchor circle)
			)
			(primitives
				(gr_poly
					(pts
						(arc
							(start -0.254 0.1778)
							(mid -0.239121 0.213721)
							(end -0.2032 0.2286)
						)
						(arc
							(start 0.2032 0.2286)
							(mid 0.239121 0.213721)
							(end 0.254 0.1778)
						)
						(arc
							(start 0.254 -0.1778)
							(mid 0.239121 -0.213721)
							(end 0.2032 -0.2286)
						)
						(arc
							(start -0.2032 -0.2286)
							(mid -0.239121 -0.213721)
							(end -0.254 -0.1778)
						)
					)
					(width 0)
					(fill yes)
				)
			)
		)
	)
	(footprint ""
		(layer "B.Cu")
		(at 171.8818 -12.879578 180)
		(property "Reference" "C366"
			(at 0 0 0)
			(layer "B.SilkS")
			(hide yes)
			(effects
				(font
					(size 1.27 1.27)
				)
				(justify mirror)
			)
		)
		(property "Value" "SC47U6D3V5MX-1-GP"
			(at 0 -4.9022 180)
			(unlocked yes)
			(layer "B.Fab")
			(hide yes)
			(effects
				(font
					(size 1.016 1.016)
					(thickness 0.1524)
				)
				(justify mirror)
			)
		)
		(property "Device Type" "C805H54"
			(at 0 -6.8072 180)
			(unlocked yes)
			(layer "B.Fab")
			(hide yes)
			(effects
				(font
					(size 1.016 1.016)
					(thickness 0.1524)
				)
				(justify mirror)
			)
		)
		(duplicate_pad_numbers_are_jumpers no)
		(fp_line
			(start -0.6096 0)
			(end 0.6096 0)
			(stroke
				(width 0.3048)
				(type default)
			)
			(layer "B.SilkS")
		)
		(fp_poly
			(pts
				(xy 0.9017 1.4351) (xy -0.9017 1.4351) (xy -0.9017 -1.4351) (xy 0.9017 -1.4351)
			)
			(stroke
				(width 0)
				(type default)
			)
			(fill no)
			(layer "B.CrtYd")
		)
		(fp_poly
			(pts
				(xy -0.9017 1.4351) (xy -0.9017 -1.4351) (xy 0.9017 -1.4351) (xy 0.9017 1.4351)
			)
			(stroke
				(width 0)
				(type default)
			)
			(fill no)
			(layer "B.Fab")
		)
		(pad "1" smd rect
			(at 0 -0.8382)
			(size 1.5494 0.9398)
			(layers "B.Cu" "B.Mask" "B.Paste")
			(net "PV_VDDR")
		)
		(pad "2" smd rect
			(at 0 0.8382)
			(size 1.5494 0.9398)
			(layers "B.Cu" "B.Mask" "B.Paste")
			(net "GND")
		)
	)
	(footprint ""
		(layer "B.Cu")
		(at 93.853 -14.097 180)
		(property "Reference" "C320"
			(at 0 0 0)
			(layer "B.SilkS")
			(hide yes)
			(effects
				(font
					(size 1.27 1.27)
				)
				(justify mirror)
			)
		)
		(property "Value" "SC22U25V5MX-GP"
			(at 0 -4.9022 180)
			(unlocked yes)
			(layer "B.Fab")
			(hide yes)
			(effects
				(font
					(size 1.016 1.016)
					(thickness 0.1524)
				)
				(justify mirror)
			)
		)
		(property "Device Type" "C805H58"
			(at 0 -6.8072 180)
			(unlocked yes)
			(layer "B.Fab")
			(hide yes)
			(effects
				(font
					(size 1.016 1.016)
					(thickness 0.1524)
				)
				(justify mirror)
			)
		)
		(duplicate_pad_numbers_are_jumpers no)
		(fp_line
			(start -0.6096 0)
			(end 0.6096 0)
			(stroke
				(width 0.3048)
				(type default)
			)
			(layer "B.SilkS")
		)
		(fp_poly
			(pts
				(xy 0.9017 1.4351) (xy -0.9017 1.4351) (xy -0.9017 -1.4351) (xy 0.9017 -1.4351)
			)
			(stroke
				(width 0)
				(type default)
			)
			(fill no)
			(layer "B.CrtYd")
		)
		(fp_poly
			(pts
				(xy -0.9017 1.4351) (xy -0.9017 -1.4351) (xy 0.9017 -1.4351) (xy 0.9017 1.4351)
			)
			(stroke
				(width 0)
				(type default)
			)
			(fill no)
			(layer "B.Fab")
		)
		(pad "1" smd rect
			(at 0 -0.8382)
			(size 1.5494 0.9398)
			(layers "B.Cu" "B.Mask" "B.Paste")
			(net "P12V")
		)
		(pad "2" smd rect
			(at 0 0.8382)
			(size 1.5494 0.9398)
			(layers "B.Cu" "B.Mask" "B.Paste")
			(net "GND")
		)
	)
	(footprint ""
		(layer "B.Cu")
		(at 36.449 -20.447 180)
		(property "Reference" "R452"
			(at 0 0 0)
			(layer "B.SilkS")
			(hide yes)
			(effects
				(font
					(size 1.27 1.27)
				)
				(justify mirror)
			)
		)
		(property "Value" "4K7R2F-GP"
			(at -1.7907 -1.1176 180)
			(unlocked yes)
			(layer "B.Fab")
			(hide yes)
			(effects
				(font
					(size 1.016 1.016)
					(thickness 0.1524)
				)
				(justify mirror)
			)
		)
		(property "Device Type" "R402H16"
			(at -1.7907 -2.6416 180)
			(unlocked yes)
			(layer "B.Fab")
			(hide yes)
			(effects
				(font
					(size 1.016 1.016)
					(thickness 0.1524)
				)
				(justify mirror)
			)
		)
		(duplicate_pad_numbers_are_jumpers no)
		(fp_rect
			(start 0.381 0.8382)
			(end -0.381 -0.8382)
			(stroke
				(width 0)
				(type default)
			)
			(fill no)
			(layer "B.CrtYd")
		)
		(fp_rect
			(start 0.381 0.8382)
			(end -0.381 -0.8382)
			(stroke
				(width 0)
				(type default)
			)
			(fill no)
			(layer "B.Fab")
		)
		(pad "1" smd custom
			(at 0 -0.4318)
			(size 0.127 0.127)
			(layers "B.Cu" "B.Mask" "B.Paste")
			(net "CLKBUFF_BYPASS_OR_PLL")
			(options
				(clearance outline)
				(anchor circle)
			)
			(primitives
				(gr_poly
					(pts
						(arc
							(start -0.2032 0.2794)
							(mid -0.239121 0.264521)
							(end -0.254 0.2286)
						)
						(arc
							(start -0.254 -0.2286)
							(mid -0.239121 -0.264521)
							(end -0.2032 -0.2794)
						)
						(arc
							(start 0.2032 -0.2794)
							(mid 0.239121 -0.264521)
							(end 0.254 -0.2286)
						)
						(arc
							(start 0.254 0.2286)
							(mid 0.239121 0.264521)
							(end 0.2032 0.2794)
						)
					)
					(width 0)
					(fill yes)
				)
			)
		)
		(pad "2" smd custom
			(at 0 0.4318)
			(size 0.127 0.127)
			(layers "B.Cu" "B.Mask" "B.Paste")
			(net "GND")
			(options
				(clearance outline)
				(anchor circle)
			)
			(primitives
				(gr_poly
					(pts
						(arc
							(start -0.2032 0.2794)
							(mid -0.239121 0.264521)
							(end -0.254 0.2286)
						)
						(arc
							(start -0.254 -0.2286)
							(mid -0.239121 -0.264521)
							(end -0.2032 -0.2794)
						)
						(arc
							(start 0.2032 -0.2794)
							(mid 0.239121 -0.264521)
							(end 0.254 -0.2286)
						)
						(arc
							(start 0.254 0.2286)
							(mid 0.239121 0.264521)
							(end 0.2032 0.2794)
						)
					)
					(width 0)
					(fill yes)
				)
			)
		)
	)
)
